G04 ================== begin FILE IDENTIFICATION RECORD ==================*
G04 Layout Name:  13919-sa.brd*
G04 Film Name:    BSMD*
G04 File Format:  Gerber RS274X*
G04 File Origin:  Cadence Allegro 16.5-S039*
G04 Origin Date:  Fri Nov 22 15:26:59 2013*
G04 *
G04 Layer:  VIA CLASS/PASTEMASK_BOTTOM*
G04 Layer:  PIN/PASTEMASK_BOTTOM*
G04 Layer:  PACKAGE GEOMETRY/PASTEMASK_BOTTOM*
G04 Layer:  DRAWING FORMAT/LAYER_PCB_STORY*
G04 Layer:  DRAWING FORMAT/LAYER_PAST_B*
G04 Layer:  BOARD GEOMETRY/PANEL_OUTLINE*
G04 *
G04 Offset:    (0.00 0.00)*
G04 Mirror:    No*
G04 Mode:      Positive*
G04 Rotation:  0*
G04 FullContactRelief:  No*
G04 UndefLineWidth:     6.00*
G04 ================== end FILE IDENTIFICATION RECORD ====================*
%FSLAX35Y35*MOIN*%
%IR0*IPPOS*OFA0.00000B0.00000*MIA0B0*SFA1.00000B1.00000*%
%ADD10C,.02*%
%ADD11C,.006*%
G75*
%LPD*%
G75*
G54D10*
G01X-67189Y-77263D02*
G02I-12000J0D01*
G01X-72339D02*
G02I-6850J0D01*
G01X-79189Y-93263D02*
Y-61263D01*
G01X-63189Y-77263D02*
X-95189D01*
G01X-63189Y-93263D02*
Y-173263D01*
G01D02*
X1156611D01*
G01X-63189Y-93263D02*
X1156611D01*
G01X-63189Y-128763D02*
X1156611D01*
G01X369111Y-93263D02*
Y-173263D01*
G01X506611Y-93263D02*
Y-173263D01*
G01X621611Y-93263D02*
Y-173263D01*
G01X789111Y-93263D02*
Y-173263D01*
G01X959111Y-93263D02*
Y-173263D01*
G01X1156611Y-93263D02*
Y-173263D01*
G01X1184611Y-77263D02*
G02I-12000J0D01*
G01X1179461D02*
G02I-6850J0D01*
G01X1172611Y-93263D02*
Y-61263D01*
G01X1188611Y-77263D02*
X1156611D01*
G54D11*
G01X-44374Y-163263D02*
Y-145763D01*
G01X-35204D02*
Y-163263D01*
G01Y-154513D02*
X-44374D01*
G01X-22289Y-163263D02*
X-23599Y-162971D01*
X-24909Y-161805D01*
X-25783Y-159763D01*
X-26219Y-157430D01*
X-25783Y-155096D01*
X-24909Y-153055D01*
X-23599Y-151888D01*
X-22289Y-151597D01*
X-20979Y-151888D01*
X-19669Y-153055D01*
X-18796Y-155096D01*
X-18577Y-157430D01*
X-18796Y-159763D01*
X-19669Y-161805D01*
X-20979Y-162971D01*
X-22289Y-163263D01*
G01X-8501D02*
Y-151597D01*
G01Y-154513D02*
X-7627Y-153055D01*
X-6317Y-151888D01*
X-4571Y-151597D01*
X-3043Y-151888D01*
X-1732Y-153055D01*
X-1077Y-155096D01*
Y-163263D01*
G01X9436Y-155388D02*
X16423D01*
X15768Y-153346D01*
X14676Y-152180D01*
X13148Y-151597D01*
X11619Y-151888D01*
X10309Y-152763D01*
X9436Y-154805D01*
X8999Y-156555D01*
Y-158305D01*
X9436Y-160055D01*
X10528Y-161805D01*
X11838Y-162971D01*
X13366Y-163263D01*
X14894Y-162680D01*
X16423Y-160930D01*
G01X25626Y-168513D02*
X26936Y-169096D01*
X28683Y-168513D01*
X29774Y-167347D01*
X30648Y-165888D01*
X31957Y-161222D01*
X34796Y-151597D01*
G01X27809D02*
X31957Y-161222D01*
G01X66957Y-153930D02*
X67831Y-153055D01*
X68486Y-151597D01*
X68923Y-149554D01*
X68486Y-147805D01*
X67613Y-146638D01*
X66084Y-145763D01*
X60189D01*
Y-163263D01*
X67394D01*
X68923Y-162097D01*
X69796Y-160346D01*
X70233Y-158305D01*
X69796Y-156263D01*
X68486Y-154513D01*
X66957Y-153930D01*
X60189D01*
G01X86641Y-163263D02*
Y-151597D01*
G01Y-153638D02*
X85768Y-152472D01*
X84457Y-151888D01*
X82929Y-151597D01*
X81401Y-152180D01*
X80091Y-153346D01*
X79217Y-155096D01*
X78781Y-157430D01*
X79217Y-159763D01*
X80091Y-161513D01*
X81401Y-162680D01*
X82929Y-163263D01*
X84457Y-162971D01*
X85768Y-162097D01*
X86641Y-160930D01*
G01X104141Y-145763D02*
Y-163263D01*
G01Y-160639D02*
X103268Y-162097D01*
X101957Y-162971D01*
X100429Y-163263D01*
X98683Y-162680D01*
X97373Y-161222D01*
X96499Y-159472D01*
X96281Y-157430D01*
X96499Y-155388D01*
X97373Y-153638D01*
X98683Y-152180D01*
X100429Y-151597D01*
X101957Y-151888D01*
X103049Y-152472D01*
X104141Y-153638D01*
G01X114654Y-167638D02*
X116183Y-168805D01*
X117929Y-169096D01*
X119457Y-168805D01*
X120768Y-167347D01*
X121641Y-165305D01*
Y-151597D01*
G01Y-153930D02*
X120768Y-152763D01*
X119457Y-151888D01*
X117929Y-151597D01*
X116183Y-152180D01*
X115091Y-153346D01*
X114217Y-155388D01*
X113781Y-157430D01*
X113999Y-159180D01*
X114873Y-161222D01*
X116183Y-162680D01*
X117929Y-163263D01*
X119239Y-162971D01*
X120768Y-161805D01*
X121641Y-160639D01*
G01X131936Y-155388D02*
X138923D01*
X138268Y-153346D01*
X137176Y-152180D01*
X135648Y-151597D01*
X134119Y-151888D01*
X132809Y-152763D01*
X131936Y-154805D01*
X131499Y-156555D01*
Y-158305D01*
X131936Y-160055D01*
X133028Y-161805D01*
X134338Y-162971D01*
X135866Y-163263D01*
X137394Y-162680D01*
X138923Y-160930D01*
G01X149654Y-163263D02*
Y-151597D01*
G01Y-153930D02*
X150746Y-152763D01*
X151838Y-151888D01*
X153366Y-151597D01*
X154457Y-151888D01*
X155768Y-152763D01*
G01X183344Y-163263D02*
Y-145763D01*
X188803D01*
X190549Y-146638D01*
X191641Y-147805D01*
X192078Y-150138D01*
X191641Y-152472D01*
X190331Y-153930D01*
X188803Y-154805D01*
X183344D01*
G01X188803D02*
X192078Y-163263D01*
G01X205211Y-151597D02*
Y-163263D01*
G01Y-146930D02*
X204774Y-146638D01*
Y-146055D01*
X205211Y-145763D01*
X205648Y-146055D01*
Y-146638D01*
X205211Y-146930D01*
G01X219436Y-161222D02*
X220528Y-162388D01*
X222056Y-163263D01*
X223366D01*
X224676Y-162680D01*
X225549Y-161805D01*
X225986Y-160639D01*
X225768Y-158888D01*
X224894Y-158013D01*
X220964Y-156263D01*
X220091Y-154221D01*
X220528Y-152763D01*
X221401Y-151888D01*
X222711Y-151597D01*
X224021Y-151888D01*
X225331Y-152763D01*
G01X236936Y-155388D02*
X243923D01*
X243268Y-153346D01*
X242176Y-152180D01*
X240648Y-151597D01*
X239119Y-151888D01*
X237809Y-152763D01*
X236936Y-154805D01*
X236499Y-156555D01*
Y-158305D01*
X236936Y-160055D01*
X238028Y-161805D01*
X239338Y-162971D01*
X240866Y-163263D01*
X242394Y-162680D01*
X243923Y-160930D01*
G01X254654Y-163263D02*
Y-151597D01*
G01Y-153930D02*
X255746Y-152763D01*
X256838Y-151888D01*
X258366Y-151597D01*
X259457Y-151888D01*
X260768Y-152763D01*
G01X297514Y-147222D02*
X296204Y-146346D01*
X294676Y-145763D01*
X292929D01*
X290964Y-146638D01*
X289436Y-148096D01*
X288344Y-149847D01*
X287471Y-152763D01*
X287252Y-155388D01*
X287689Y-158013D01*
X288344Y-159763D01*
X289654Y-161513D01*
X291183Y-162680D01*
X292711Y-163263D01*
X294239D01*
X295768Y-162680D01*
X297078Y-161805D01*
X298170Y-160639D01*
G01X314141Y-163263D02*
Y-151597D01*
G01Y-153638D02*
X313268Y-152472D01*
X311957Y-151888D01*
X310429Y-151597D01*
X308901Y-152180D01*
X307591Y-153346D01*
X306717Y-155096D01*
X306281Y-157430D01*
X306717Y-159763D01*
X307591Y-161513D01*
X308901Y-162680D01*
X310429Y-163263D01*
X311957Y-162971D01*
X313268Y-162097D01*
X314141Y-160930D01*
G01X324654Y-163263D02*
Y-151597D01*
G01Y-153930D02*
X325746Y-152763D01*
X326838Y-151888D01*
X328366Y-151597D01*
X329457Y-151888D01*
X330768Y-152763D01*
G01X349141Y-145763D02*
Y-163263D01*
G01Y-160639D02*
X348268Y-162097D01*
X346957Y-162971D01*
X345429Y-163263D01*
X343683Y-162680D01*
X342373Y-161222D01*
X341499Y-159472D01*
X341281Y-157430D01*
X341499Y-155388D01*
X342373Y-153638D01*
X343683Y-152180D01*
X345429Y-151597D01*
X346957Y-151888D01*
X348049Y-152472D01*
X349141Y-153638D01*
G01X112034Y-118263D02*
Y-100763D01*
X117711Y-115346D01*
X123388Y-100763D01*
Y-118263D01*
G01X135211D02*
X133901Y-117971D01*
X132591Y-116805D01*
X131717Y-114763D01*
X131281Y-112430D01*
X131717Y-110096D01*
X132591Y-108055D01*
X133901Y-106888D01*
X135211Y-106597D01*
X136521Y-106888D01*
X137831Y-108055D01*
X138704Y-110096D01*
X138923Y-112430D01*
X138704Y-114763D01*
X137831Y-116805D01*
X136521Y-117971D01*
X135211Y-118263D01*
G01X156641Y-100763D02*
Y-118263D01*
G01Y-115639D02*
X155768Y-117097D01*
X154457Y-117971D01*
X152929Y-118263D01*
X151183Y-117680D01*
X149873Y-116222D01*
X148999Y-114472D01*
X148781Y-112430D01*
X148999Y-110388D01*
X149873Y-108638D01*
X151183Y-107180D01*
X152929Y-106597D01*
X154457Y-106888D01*
X155549Y-107472D01*
X156641Y-108638D01*
G01X166936Y-110388D02*
X173923D01*
X173268Y-108346D01*
X172176Y-107180D01*
X170648Y-106597D01*
X169119Y-106888D01*
X167809Y-107763D01*
X166936Y-109805D01*
X166499Y-111555D01*
Y-113305D01*
X166936Y-115055D01*
X168028Y-116805D01*
X169338Y-117971D01*
X170866Y-118263D01*
X172394Y-117680D01*
X173923Y-115930D01*
G01X187711Y-118263D02*
Y-100763D01*
G01X402811Y-163263D02*
Y-145763D01*
X400191Y-149263D01*
G01Y-163263D02*
X405431D01*
G01X415508Y-159763D02*
X416817Y-161805D01*
X418564Y-162971D01*
X420529Y-163263D01*
X422276Y-162971D01*
X424023Y-161513D01*
X425114Y-159763D01*
X425333Y-158013D01*
X424896Y-155972D01*
X423368Y-154513D01*
X421839Y-153930D01*
X419874D01*
G01X421839D02*
X423149Y-153055D01*
X424241Y-151597D01*
X424678Y-149847D01*
X424241Y-148096D01*
X423149Y-146638D01*
X421184Y-145763D01*
X419219Y-146055D01*
X417254Y-147222D01*
G01X434099Y-161222D02*
X435628Y-162680D01*
X437374Y-163263D01*
X439121Y-162680D01*
X440649Y-160930D01*
X441741Y-158305D01*
X442178Y-155680D01*
Y-152472D01*
X441741Y-149847D01*
X440649Y-147513D01*
X439339Y-146346D01*
X437811Y-145763D01*
X436064Y-146346D01*
X434754Y-147513D01*
X433881Y-149263D01*
X433444Y-151597D01*
X433881Y-153638D01*
X434973Y-155680D01*
X436283Y-156847D01*
X437811Y-157138D01*
X439557Y-156555D01*
X440868Y-155096D01*
X442178Y-152472D01*
G01X455311Y-163263D02*
Y-145763D01*
X452691Y-149263D01*
G01Y-163263D02*
X457931D01*
G01X469099Y-161222D02*
X470628Y-162680D01*
X472374Y-163263D01*
X474121Y-162680D01*
X475649Y-160930D01*
X476741Y-158305D01*
X477178Y-155680D01*
Y-152472D01*
X476741Y-149847D01*
X475649Y-147513D01*
X474339Y-146346D01*
X472811Y-145763D01*
X471064Y-146346D01*
X469754Y-147513D01*
X468881Y-149263D01*
X468444Y-151597D01*
X468881Y-153638D01*
X469973Y-155680D01*
X471283Y-156847D01*
X472811Y-157138D01*
X474557Y-156555D01*
X475868Y-155096D01*
X477178Y-152472D01*
G01X389694Y-118263D02*
Y-100763D01*
X394934D01*
X396681Y-101638D01*
X397991Y-103680D01*
X398428Y-106013D01*
X397991Y-108346D01*
X396899Y-110096D01*
X394934Y-110972D01*
X389694D01*
G01X416364Y-102222D02*
X415054Y-101346D01*
X413526Y-100763D01*
X411779D01*
X409814Y-101638D01*
X408286Y-103096D01*
X407194Y-104847D01*
X406321Y-107763D01*
X406102Y-110388D01*
X406539Y-113013D01*
X407194Y-114763D01*
X408504Y-116513D01*
X410033Y-117680D01*
X411561Y-118263D01*
X413089D01*
X414618Y-117680D01*
X415928Y-116805D01*
X417020Y-115639D01*
G01X430807Y-108930D02*
X431681Y-108055D01*
X432336Y-106597D01*
X432773Y-104554D01*
X432336Y-102805D01*
X431463Y-101638D01*
X429934Y-100763D01*
X424039D01*
Y-118263D01*
X431244D01*
X432773Y-117097D01*
X433646Y-115346D01*
X434083Y-113305D01*
X433646Y-111263D01*
X432336Y-109513D01*
X430807Y-108930D01*
X424039D01*
G01X440011Y-124096D02*
X453111D01*
G01X459039Y-118263D02*
Y-100763D01*
X469083Y-118263D01*
Y-100763D01*
G01X481561Y-118263D02*
X479814Y-117971D01*
X478286Y-116805D01*
X476976Y-115055D01*
X476102Y-113013D01*
X475666Y-110680D01*
Y-108346D01*
X476102Y-106013D01*
X476976Y-103971D01*
X478286Y-102222D01*
X479814Y-101055D01*
X481561Y-100763D01*
X483307Y-101055D01*
X484836Y-102222D01*
X486146Y-103971D01*
X487020Y-106013D01*
X487456Y-108346D01*
Y-110680D01*
X487020Y-113013D01*
X486146Y-115055D01*
X484836Y-116805D01*
X483307Y-117971D01*
X481561Y-118263D01*
G01X532402Y-100763D02*
X537861Y-118263D01*
X543320Y-100763D01*
G01X559728Y-118263D02*
X550994D01*
Y-100763D01*
X559728D01*
G01X556234Y-109221D02*
X550994D01*
G01X568494Y-118263D02*
Y-100763D01*
X573953D01*
X575699Y-101638D01*
X576791Y-102805D01*
X577228Y-105138D01*
X576791Y-107472D01*
X575481Y-108930D01*
X573953Y-109805D01*
X568494D01*
G01X573953D02*
X577228Y-118263D01*
G01X590361Y-118846D02*
X589924Y-118555D01*
Y-117971D01*
X590361Y-117680D01*
X590798Y-117971D01*
Y-118555D01*
X590361Y-118846D01*
G01X550776Y-160930D02*
X552523Y-162388D01*
X554488Y-163263D01*
X556234D01*
X557981Y-162388D01*
X559291Y-160930D01*
X559946Y-158888D01*
X559509Y-156847D01*
X558418Y-155096D01*
X556453Y-153930D01*
X553833Y-153346D01*
X552304Y-152180D01*
X551649Y-150138D01*
X552086Y-148096D01*
X553178Y-146638D01*
X554706Y-145763D01*
X556234D01*
X557763Y-146346D01*
X559073Y-147805D01*
G01X567402Y-163263D02*
X572861Y-145763D01*
X578320Y-163263D01*
G01X576354Y-157138D02*
X569367D01*
G01X729815Y-153930D02*
X728941Y-153055D01*
X728286Y-151597D01*
X727849Y-149554D01*
X728286Y-147805D01*
X729159Y-146638D01*
X730688Y-145763D01*
X736583D01*
Y-163263D01*
X729378D01*
X727849Y-162097D01*
X726976Y-160346D01*
X726539Y-158305D01*
X726976Y-156263D01*
X728286Y-154513D01*
X729815Y-153930D01*
X736583D01*
G01X718646Y-160930D02*
X716899Y-162388D01*
X714934Y-163263D01*
X713188D01*
X711441Y-162388D01*
X710131Y-160930D01*
X709476Y-158888D01*
X709913Y-156847D01*
X711004Y-155096D01*
X712969Y-153930D01*
X715589Y-153346D01*
X717118Y-152180D01*
X717773Y-150138D01*
X717336Y-148096D01*
X716244Y-146638D01*
X714716Y-145763D01*
X713188D01*
X711659Y-146346D01*
X710349Y-147805D01*
G01X702238Y-163263D02*
Y-145763D01*
X696561Y-160346D01*
X690884Y-145763D01*
Y-163263D01*
G01X683864D02*
Y-145763D01*
X679498D01*
X677751Y-146638D01*
X676441Y-147805D01*
X675349Y-149554D01*
X674476Y-151597D01*
X674258Y-154513D01*
X674476Y-157430D01*
X675349Y-159472D01*
X676441Y-161222D01*
X677751Y-162388D01*
X679498Y-163263D01*
X683864D01*
G01X665944Y-100763D02*
Y-118263D01*
X674678D01*
G01X691741D02*
Y-106597D01*
G01Y-108638D02*
X690868Y-107472D01*
X689557Y-106888D01*
X688029Y-106597D01*
X686501Y-107180D01*
X685191Y-108346D01*
X684317Y-110096D01*
X683881Y-112430D01*
X684317Y-114763D01*
X685191Y-116513D01*
X686501Y-117680D01*
X688029Y-118263D01*
X689557Y-117971D01*
X690868Y-117097D01*
X691741Y-115930D01*
G01X700726Y-123513D02*
X702036Y-124096D01*
X703783Y-123513D01*
X704874Y-122347D01*
X705748Y-120888D01*
X707057Y-116222D01*
X709896Y-106597D01*
G01X702909D02*
X707057Y-116222D01*
G01X719536Y-110388D02*
X726523D01*
X725868Y-108346D01*
X724776Y-107180D01*
X723248Y-106597D01*
X721719Y-106888D01*
X720409Y-107763D01*
X719536Y-109805D01*
X719099Y-111555D01*
Y-113305D01*
X719536Y-115055D01*
X720628Y-116805D01*
X721938Y-117971D01*
X723466Y-118263D01*
X724994Y-117680D01*
X726523Y-115930D01*
G01X737254Y-118263D02*
Y-106597D01*
G01Y-108930D02*
X738346Y-107763D01*
X739438Y-106888D01*
X740966Y-106597D01*
X742057Y-106888D01*
X743368Y-107763D01*
G01X808058Y-118263D02*
Y-100763D01*
X812424D01*
X814171Y-101638D01*
X815481Y-102805D01*
X816573Y-104554D01*
X817446Y-106597D01*
X817664Y-109513D01*
X817446Y-112430D01*
X816573Y-114472D01*
X815481Y-116222D01*
X814171Y-117388D01*
X812424Y-118263D01*
X808058D01*
G01X827086Y-110388D02*
X834073D01*
X833418Y-108346D01*
X832326Y-107180D01*
X830798Y-106597D01*
X829269Y-106888D01*
X827959Y-107763D01*
X827086Y-109805D01*
X826649Y-111555D01*
Y-113305D01*
X827086Y-115055D01*
X828178Y-116805D01*
X829488Y-117971D01*
X831016Y-118263D01*
X832544Y-117680D01*
X834073Y-115930D01*
G01X844586Y-116222D02*
X845678Y-117388D01*
X847206Y-118263D01*
X848516D01*
X849826Y-117680D01*
X850699Y-116805D01*
X851136Y-115639D01*
X850918Y-113888D01*
X850044Y-113013D01*
X846114Y-111263D01*
X845241Y-109221D01*
X845678Y-107763D01*
X846551Y-106888D01*
X847861Y-106597D01*
X849171Y-106888D01*
X850481Y-107763D01*
G01X865361Y-106597D02*
Y-118263D01*
G01Y-101930D02*
X864924Y-101638D01*
Y-101055D01*
X865361Y-100763D01*
X865798Y-101055D01*
Y-101638D01*
X865361Y-101930D01*
G01X879804Y-122638D02*
X881333Y-123805D01*
X883079Y-124096D01*
X884607Y-123805D01*
X885918Y-122347D01*
X886791Y-120305D01*
Y-106597D01*
G01Y-108930D02*
X885918Y-107763D01*
X884607Y-106888D01*
X883079Y-106597D01*
X881333Y-107180D01*
X880241Y-108346D01*
X879367Y-110388D01*
X878931Y-112430D01*
X879149Y-114180D01*
X880023Y-116222D01*
X881333Y-117680D01*
X883079Y-118263D01*
X884389Y-117971D01*
X885918Y-116805D01*
X886791Y-115639D01*
G01X896649Y-118263D02*
Y-106597D01*
G01Y-109513D02*
X897523Y-108055D01*
X898833Y-106888D01*
X900579Y-106597D01*
X902107Y-106888D01*
X903418Y-108055D01*
X904073Y-110096D01*
Y-118263D01*
G01X914586Y-110388D02*
X921573D01*
X920918Y-108346D01*
X919826Y-107180D01*
X918298Y-106597D01*
X916769Y-106888D01*
X915459Y-107763D01*
X914586Y-109805D01*
X914149Y-111555D01*
Y-113305D01*
X914586Y-115055D01*
X915678Y-116805D01*
X916988Y-117971D01*
X918516Y-118263D01*
X920044Y-117680D01*
X921573Y-115930D01*
G01X932304Y-118263D02*
Y-106597D01*
G01Y-108930D02*
X933396Y-107763D01*
X934488Y-106888D01*
X936016Y-106597D01*
X937107Y-106888D01*
X938418Y-107763D01*
G01X853991Y-145763D02*
X859231D01*
G01X856611D02*
Y-163263D01*
G01X853991D02*
X859231D01*
G01X868652Y-145763D02*
X874111Y-163263D01*
X879570Y-145763D01*
G01X891611Y-163263D02*
Y-155388D01*
X887244Y-145763D01*
G01X895978D02*
X891611Y-155388D01*
G01X979061Y-163263D02*
Y-145763D01*
X976441Y-149263D01*
G01Y-163263D02*
X981681D01*
G01X996561D02*
Y-145763D01*
X993941Y-149263D01*
G01Y-163263D02*
X999181D01*
G01X1010131Y-163846D02*
X1017991Y-145763D01*
G01X1027413Y-148680D02*
X1028723Y-146930D01*
X1030251Y-146055D01*
X1031998Y-145763D01*
X1034181Y-146346D01*
X1035709Y-147805D01*
X1036146Y-149554D01*
X1035928Y-151305D01*
X1035054Y-152763D01*
X1030688Y-155680D01*
X1028723Y-157721D01*
X1027413Y-160639D01*
X1026976Y-163263D01*
X1036146D01*
G01X1044913Y-148680D02*
X1046223Y-146930D01*
X1047751Y-146055D01*
X1049498Y-145763D01*
X1051681Y-146346D01*
X1053209Y-147805D01*
X1053646Y-149554D01*
X1053428Y-151305D01*
X1052554Y-152763D01*
X1048188Y-155680D01*
X1046223Y-157721D01*
X1044913Y-160639D01*
X1044476Y-163263D01*
X1053646D01*
G01X1062631Y-163846D02*
X1070491Y-145763D01*
G01X1079913Y-148680D02*
X1081223Y-146930D01*
X1082751Y-146055D01*
X1084498Y-145763D01*
X1086681Y-146346D01*
X1088209Y-147805D01*
X1088646Y-149554D01*
X1088428Y-151305D01*
X1087554Y-152763D01*
X1083188Y-155680D01*
X1081223Y-157721D01*
X1079913Y-160639D01*
X1079476Y-163263D01*
X1088646D01*
G01X1101561Y-145763D02*
X1099814Y-146346D01*
X1098504Y-147805D01*
X1097631Y-149554D01*
X1096976Y-151888D01*
X1096758Y-154513D01*
X1096976Y-157138D01*
X1097631Y-159472D01*
X1098504Y-161222D01*
X1099814Y-162680D01*
X1101561Y-163263D01*
X1103307Y-162680D01*
X1104618Y-161222D01*
X1105491Y-159472D01*
X1106146Y-157138D01*
X1106364Y-154513D01*
X1106146Y-151888D01*
X1105491Y-149554D01*
X1104618Y-147805D01*
X1103307Y-146346D01*
X1101561Y-145763D01*
G01X1119061Y-163263D02*
Y-145763D01*
X1116441Y-149263D01*
G01Y-163263D02*
X1121681D01*
G01X1131758Y-159763D02*
X1133067Y-161805D01*
X1134814Y-162971D01*
X1136779Y-163263D01*
X1138526Y-162971D01*
X1140273Y-161513D01*
X1141364Y-159763D01*
X1141583Y-158013D01*
X1141146Y-155972D01*
X1139618Y-154513D01*
X1138089Y-153930D01*
X1136124D01*
G01X1138089D02*
X1139399Y-153055D01*
X1140491Y-151597D01*
X1140928Y-149847D01*
X1140491Y-148096D01*
X1139399Y-146638D01*
X1137434Y-145763D01*
X1135469Y-146055D01*
X1133504Y-147222D01*
G01X1026758Y-118263D02*
Y-100763D01*
X1031124D01*
X1032871Y-101638D01*
X1034181Y-102805D01*
X1035273Y-104554D01*
X1036146Y-106597D01*
X1036364Y-109513D01*
X1036146Y-112430D01*
X1035273Y-114472D01*
X1034181Y-116222D01*
X1032871Y-117388D01*
X1031124Y-118263D01*
X1026758D01*
G01X1052991D02*
Y-106597D01*
G01Y-108638D02*
X1052118Y-107472D01*
X1050807Y-106888D01*
X1049279Y-106597D01*
X1047751Y-107180D01*
X1046441Y-108346D01*
X1045567Y-110096D01*
X1045131Y-112430D01*
X1045567Y-114763D01*
X1046441Y-116513D01*
X1047751Y-117680D01*
X1049279Y-118263D01*
X1050807Y-117971D01*
X1052118Y-117097D01*
X1052991Y-115930D01*
G01X1066561Y-100763D02*
Y-118263D01*
G01X1063504Y-106597D02*
X1069618D01*
G01X1080786Y-110388D02*
X1087773D01*
X1087118Y-108346D01*
X1086026Y-107180D01*
X1084498Y-106597D01*
X1082969Y-106888D01*
X1081659Y-107763D01*
X1080786Y-109805D01*
X1080349Y-111555D01*
Y-113305D01*
X1080786Y-115055D01*
X1081878Y-116805D01*
X1083188Y-117971D01*
X1084716Y-118263D01*
X1086244Y-117680D01*
X1087773Y-115930D01*
G01X-20271Y15000D02*
Y676339D01*
G01Y15000D02*
G03X-5271Y0I15000J0D01*
G01Y691339D02*
G03X-20271Y676339I0J-15000D01*
G01X0Y37795D02*
G03X3937Y33858I3937J0D01*
G01X21063Y29921D02*
G03X17126Y33858I-3937J0D01*
G01X3937D02*
X17126D01*
G01X299409Y0D02*
X23031D01*
G01X21063Y1969D02*
X23031Y0D01*
G01X21063Y1969D02*
Y29921D01*
G01X0Y102756D02*
Y37795D01*
G01D02*
G03X-7874I-3937J0D01*
G01X3937Y25984D02*
X13189D01*
G01X-7874Y37795D02*
G03X3937Y25984I11811J0D01*
G01X13189Y0D02*
X-5271D01*
G01X13189Y25984D02*
Y0D01*
G01X3937Y106693D02*
G03X0Y102756I0J-3937D01*
G01X-7874Y68504D02*
G03X0I3937J0D01*
G01X-7874D02*
Y122737D01*
G01X0Y118504D02*
G03X3937Y114567I3937J0D01*
G01Y157382D02*
G03X0Y153445I0J-3937D01*
G01X17126Y157382D02*
G03X21063Y161319I0J3937D01*
G01X0Y118504D02*
Y153445D01*
G01X21063Y219292D02*
Y161319D01*
G01D02*
Y187402D01*
G01X143701Y114567D02*
X3937D01*
G01Y157382D02*
X17126D01*
G01X3937Y106693D02*
X143701D01*
G01X-7874Y153445D02*
Y157382D01*
G01Y153445D02*
G03X0I3937J0D01*
G01Y122737D02*
G03X-7874I-3937J0D01*
G01X-10433Y161070D02*
G03X-7874Y157382I3937J0D01*
G01X-10433Y265210D02*
Y161070D01*
G01X51378Y181496D02*
G03X47441Y177559I0J-3937D01*
G01Y165748D02*
G03X51378Y161811I3937J0D01*
G01X47441Y165748D02*
Y177559D01*
G01X23031Y221260D02*
X21063Y219292D01*
G01X23031Y221260D02*
X63189D01*
G01X0Y272835D02*
G03X3937Y268898I3937J0D01*
G01X21063Y264961D02*
G03X17126Y268898I-3937J0D01*
G01X3937D02*
X17126D01*
G01X299409Y235040D02*
X23031D01*
G01X21063Y237008D02*
X23031Y235040D01*
G01X21063Y237008D02*
Y264961D01*
G01X0Y337796D02*
Y272835D01*
G01D02*
G03X-7874I-3937J0D01*
G01Y268898D02*
G03X-10433Y265210I1378J-3688D01*
G01X-7874Y268898D02*
Y272835D01*
G01X3937Y341733D02*
G03X0Y337796I0J-3937D01*
G01X3937Y341733D02*
X143701D01*
G01X-7874Y303543D02*
Y357781D01*
G01Y303544D02*
G03X0I3937J0D01*
G01X47441Y400788D02*
G03X51378Y396851I3937J0D01*
G01X47441Y400788D02*
Y412599D01*
G01X0Y353544D02*
G03X3937Y349607I3937J0D01*
G01Y392422D02*
G03X0Y388485I0J-3937D01*
G01X17126Y392422D02*
G03X21063Y396359I0J3937D01*
G01X0Y353544D02*
Y388485D01*
G01X21063Y454331D02*
Y396359D01*
G01D02*
Y422441D01*
G01X143701Y349607D02*
X3937D01*
G01Y392422D02*
X17126D01*
G01X-7874Y388480D02*
Y392422D01*
G01Y388485D02*
G03X0I3937J0D01*
G01Y357776D02*
G03X-7874I-3937J0D01*
G01X-10433Y396110D02*
G03X-7874Y392422I3937J0D01*
G01X-10433Y500250D02*
Y396110D01*
G01X51378Y416536D02*
G03X47441Y412599I0J-3937D01*
G01X23031Y456300D02*
X21063Y454331D01*
G01X23031Y456300D02*
X63189D01*
G01X0Y507874D02*
G03X3937Y503937I3937J0D01*
G01X21063Y500000D02*
G03X17126Y503937I-3937J0D01*
G01X3937D02*
X17126D01*
G01X299409Y470079D02*
X23031D01*
G01X21063Y472048D02*
X23031Y470079D01*
G01X21063Y472048D02*
Y500000D01*
G01X0Y572835D02*
Y507874D01*
G01D02*
G03X-7874I-3937J0D01*
G01Y503937D02*
Y507880D01*
G01Y503937D02*
G03X-10433Y500250I1378J-3688D01*
G01X3937Y576772D02*
G03X0Y572835I0J-3937D01*
G01X3937Y576772D02*
X143701D01*
G01X0Y588583D02*
G03X3937Y584646I3937J0D01*
G01X0Y588583D02*
Y623524D01*
G01X143701Y584646D02*
X3937D01*
G01X-7874Y538578D02*
Y592823D01*
G01Y538583D02*
G03X0I3937J0D01*
G01X51378Y651576D02*
G03X47441Y647639I0J-3937D01*
G01Y635828D02*
G03X51378Y631891I3937J0D01*
G01X47441Y635828D02*
Y647639D01*
G01X3937Y627461D02*
G03X0Y623524I0J-3937D01*
G01X17126Y627461D02*
G03X21063Y631398I0J3937D01*
G01Y689371D02*
Y631398D01*
G01D02*
Y657481D01*
G01X3937Y627461D02*
X17126D01*
G01X1830Y651994D02*
G03I-4292J0D01*
G01X-7874Y623517D02*
Y623536D01*
G01X13189Y691339D02*
Y635335D01*
G01X3937D02*
X13189D01*
G01X3937D02*
G03X-7874Y623524I0J-11811D01*
G01D02*
G03X0I3937J0D01*
G01Y592816D02*
G03X-7874I-3937J0D01*
G01X23031Y691339D02*
X21063Y689371D01*
G01X23031Y691339D02*
X63189D01*
G01X13189D02*
X-5271D01*
G01X63189Y161811D02*
G03X67126Y165748I0J3937D01*
G01X73425D02*
G03X77362Y161811I3937J0D01*
G01X89173D02*
G03X93110Y165748I0J3937D01*
G01X99409D02*
G03X103346Y161811I3937J0D01*
G01X63189D02*
X51378D01*
G01X89173D02*
X77362D01*
G01X115157D02*
X103346D01*
G01X89173Y114567D02*
G03Y106693I0J-3937D01*
G01X58465D02*
G03Y114567I0J3937D01*
G01X67126Y177559D02*
G03X63189Y181496I-3937J0D01*
G01X77362D02*
G03X73425Y177559I0J-3937D01*
G01X93110D02*
G03X89173Y181496I-3937J0D01*
G01X103346D02*
G03X99409Y177559I0J-3937D01*
G01X67126D02*
Y165748D01*
G01X73425D02*
Y177559D01*
G01X93110D02*
Y165748D01*
G01X99409D02*
Y177559D01*
G01X103346Y181496D02*
X115157D01*
G01X77362D02*
X89173D01*
G01X51378D02*
X63189D01*
G01X65157Y191930D02*
G03X72638I3740J0D01*
G01X65157Y219292D02*
Y191930D01*
G01X74606Y221260D02*
X72638Y219292D01*
G01D02*
Y191930D01*
G01X65157Y219292D02*
X63189Y221260D01*
G01X74606D02*
X350984D01*
G01X89173Y349607D02*
G03Y341733I0J-3937D01*
G01X58465D02*
G03Y349607I0J3937D01*
G01X63189Y396851D02*
G03X67126Y400788I0J3937D01*
G01X73425D02*
G03X77362Y396851I3937J0D01*
G01X89173D02*
G03X93110Y400788I0J3937D01*
G01X99409D02*
G03X103346Y396851I3937J0D01*
G01X67126Y412599D02*
Y400788D01*
G01X73425D02*
Y412599D01*
G01X93110D02*
Y400788D01*
G01X99409D02*
Y412599D01*
G01X63189Y396851D02*
X51378D01*
G01X89173D02*
X77362D01*
G01X115157D02*
X103346D01*
G01X67126Y412599D02*
G03X63189Y416536I-3937J0D01*
G01X77362D02*
G03X73425Y412599I0J-3937D01*
G01X93110D02*
G03X89173Y416536I-3937J0D01*
G01X103346D02*
G03X99409Y412599I0J-3937D01*
G01X103346Y416536D02*
X115157D01*
G01X77362D02*
X89173D01*
G01X51378D02*
X63189D01*
G01X65157Y426969D02*
G03X72638I3740J0D01*
G01X65157Y454331D02*
Y426969D01*
G01X74606Y456300D02*
X72638Y454331D01*
G01D02*
Y426969D01*
G01X65157Y454331D02*
X63189Y456300D01*
G01X74606D02*
X350984D01*
G01X89173Y584646D02*
G03Y576772I0J-3937D01*
G01X58465D02*
G03Y584646I0J3937D01*
G01X67126Y647639D02*
G03X63189Y651576I-3937J0D01*
G01Y631891D02*
G03X67126Y635828I0J3937D01*
G01X73425D02*
G03X77362Y631891I3937J0D01*
G01Y651576D02*
G03X73425Y647639I0J-3937D01*
G01X93110D02*
G03X89173Y651576I-3937J0D01*
G01Y631891D02*
G03X93110Y635828I0J3937D01*
G01X103346Y651576D02*
G03X99409Y647639I0J-3937D01*
G01Y635828D02*
G03X103346Y631891I3937J0D01*
G01X67126Y647639D02*
Y635828D01*
G01X73425D02*
Y647639D01*
G01X93110D02*
Y635828D01*
G01X99409D02*
Y647639D01*
G01X63189Y631891D02*
X51378D01*
G01X89173D02*
X77362D01*
G01X115157D02*
X103346D01*
G01Y651576D02*
X115157D01*
G01X77362D02*
X89173D01*
G01X51378D02*
X63189D01*
G01X65157Y662009D02*
G03X72638I3740J0D01*
G01X65157Y689371D02*
Y662009D01*
G01X74606Y691339D02*
X72638Y689371D01*
G01D02*
Y662009D01*
G01X65157Y689371D02*
X63189Y691339D01*
G01X74606D02*
X350984D01*
G01X147638Y102756D02*
G03X151575Y98819I3937J0D01*
G01X147638Y102756D02*
G03X143701Y106693I-3937J0D01*
G01X147638Y102756D02*
G03X151575Y98819I3937J0D01*
G01X147638Y102756D02*
G03X143701Y106693I-3937J0D01*
G01X147638Y102756D02*
G03X151575Y98819I3937J0D01*
G01X147638Y102756D02*
G03X143701Y106693I-3937J0D01*
G01X151575Y98819D02*
X222441D01*
G01X115157Y161811D02*
G03X119094Y165748I0J3937D01*
G01X151575Y122441D02*
G03X147638Y118504I0J-3937D01*
G01X143701Y114567D02*
G03X147638Y118504I0J3937D01*
G01X143701Y114567D02*
X112205D01*
G01X143701D02*
G03X147638Y118504I0J3937D01*
G01X151575Y122441D02*
G03X147638Y118504I0J-3937D01*
G01X151575Y122441D02*
G03X147638Y118504I0J-3937D01*
G01X143701Y114567D02*
G03X147638Y118504I0J3937D01*
G01X222441Y122441D02*
X151575D01*
G01X143701Y106693D02*
X112205D01*
G01X119094Y177559D02*
G03X115157Y181496I-3937J0D01*
G01X119094Y177559D02*
Y165748D01*
G01X147638Y337796D02*
G03X151575Y333859I3937J0D01*
G01X147638Y337796D02*
G03X143701Y341733I-3937J0D01*
G01D02*
X112205D01*
G01X147638Y337796D02*
G03X151575Y333859I3937J0D01*
G01X147638Y337796D02*
G03X143701Y341733I-3937J0D01*
G01X147638Y337796D02*
G03X151575Y333859I3937J0D01*
G01X147638Y337796D02*
G03X143701Y341733I-3937J0D01*
G01X151575Y333859D02*
X222441D01*
G01X115157Y396851D02*
G03X119094Y400788I0J3937D01*
G01Y412599D02*
Y400788D01*
G01X151575Y357481D02*
G03X147638Y353544I0J-3937D01*
G01X143701Y349607D02*
G03X147638Y353544I0J3937D01*
G01X143701Y349607D02*
X112205D01*
G01X143701D02*
G03X147638Y353544I0J3937D01*
G01X151575Y357481D02*
G03X147638Y353544I0J-3937D01*
G01X151575Y357481D02*
G03X147638Y353544I0J-3937D01*
G01X143701Y349607D02*
G03X147638Y353544I0J3937D01*
G01X222441Y357481D02*
X151575D01*
G01X119094Y412599D02*
G03X115157Y416536I-3937J0D01*
G01X147638Y572835D02*
G03X151575Y568898I3937J0D01*
G01X147638Y572835D02*
G03X143701Y576772I-3937J0D01*
G01D02*
X112205D01*
G01X147638Y572835D02*
G03X151575Y568898I3937J0D01*
G01X147638Y572835D02*
G03X143701Y576772I-3937J0D01*
G01X147638Y572835D02*
G03X151575Y568898I3937J0D01*
G01X147638Y572835D02*
G03X143701Y576772I-3937J0D01*
G01X151575Y568898D02*
X222441D01*
G01X151575Y592520D02*
G03X147638Y588583I0J-3937D01*
G01X143701Y584646D02*
G03X147638Y588583I0J3937D01*
G01X143701Y584646D02*
X112205D01*
G01X143701D02*
G03X147638Y588583I0J3937D01*
G01X151575Y592520D02*
G03X147638Y588583I0J-3937D01*
G01X151575Y592520D02*
G03X147638Y588583I0J-3937D01*
G01X143701Y584646D02*
G03X147638Y588583I0J3937D01*
G01X119094Y647639D02*
G03X115157Y651576I-3937J0D01*
G01Y631891D02*
G03X119094Y635828I0J3937D01*
G01Y647639D02*
Y635828D01*
G01X222441Y592520D02*
X151575D01*
G01X222441Y98819D02*
G03X226378Y102756I0J3937D01*
G01X230315Y106693D02*
G03X226378Y102756I0J-3937D01*
G01X230315Y106693D02*
G03X226378Y102756I0J-3937D01*
G01X222441Y98819D02*
G03X226378Y102756I0J3937D01*
G01X222441Y98819D02*
G03X226378Y102756I0J3937D01*
G01X230315Y106693D02*
G03X226378Y102756I0J-3937D01*
G01Y118504D02*
G03X222441Y122441I-3937J0D01*
G01X226378Y118504D02*
G03X230315Y114567I3937J0D01*
G01D02*
X261811D01*
G01X226378Y118504D02*
G03X222441Y122441I-3937J0D01*
G01X226378Y118504D02*
G03X230315Y114567I3937J0D01*
G01X226378Y118504D02*
G03X222441Y122441I-3937J0D01*
G01X226378Y118504D02*
G03X230315Y114567I3937J0D01*
G01X370079D02*
X230315D01*
G01Y106693D02*
X261811D01*
G01X230315D02*
X370079D01*
G01X222441Y333859D02*
G03X226378Y337796I0J3937D01*
G01X230315Y341733D02*
G03X226378Y337796I0J-3937D01*
G01X230315Y341733D02*
X261811D01*
G01X230315D02*
G03X226378Y337796I0J-3937D01*
G01X222441Y333859D02*
G03X226378Y337796I0J3937D01*
G01X222441Y333859D02*
G03X226378Y337796I0J3937D01*
G01X230315Y341733D02*
G03X226378Y337796I0J-3937D01*
G01X230315Y341733D02*
X370079D01*
G01X226378Y353544D02*
G03X222441Y357481I-3937J0D01*
G01X226378Y353544D02*
G03X230315Y349607I3937J0D01*
G01D02*
X261811D01*
G01X226378Y353544D02*
G03X222441Y357481I-3937J0D01*
G01X226378Y353544D02*
G03X230315Y349607I3937J0D01*
G01X226378Y353544D02*
G03X222441Y357481I-3937J0D01*
G01X226378Y353544D02*
G03X230315Y349607I3937J0D01*
G01X370079D02*
X230315D01*
G01X222441Y568898D02*
G03X226378Y572835I0J3937D01*
G01X230315Y576772D02*
G03X226378Y572835I0J-3937D01*
G01X230315Y576772D02*
X261811D01*
G01X230315D02*
G03X226378Y572835I0J-3937D01*
G01X222441Y568898D02*
G03X226378Y572835I0J3937D01*
G01X222441Y568898D02*
G03X226378Y572835I0J3937D01*
G01X230315Y576772D02*
G03X226378Y572835I0J-3937D01*
G01X230315Y576772D02*
X370079D01*
G01X226378Y588583D02*
G03X222441Y592520I-3937J0D01*
G01X226378Y588583D02*
G03X230315Y584646I3937J0D01*
G01D02*
X261811D01*
G01X226378Y588583D02*
G03X222441Y592520I-3937J0D01*
G01X226378Y588583D02*
G03X230315Y584646I3937J0D01*
G01X226378Y588583D02*
G03X222441Y592520I-3937J0D01*
G01X226378Y588583D02*
G03X230315Y584646I3937J0D01*
G01X370079D02*
X230315D01*
G01X280906Y43701D02*
G03X284843Y39764I3937J0D01*
G01X270669D02*
G03X274606Y43701I0J3937D01*
G01X254921D02*
G03X258858Y39764I3937J0D01*
G01X270669D02*
X258858D01*
G01X296654D02*
X284843D01*
G01Y59449D02*
G03X280906Y55512I0J-3937D01*
G01X258858Y59449D02*
G03X254921Y55512I0J-3937D01*
G01X274606D02*
G03X270669Y59449I-3937J0D01*
G01X280906Y43701D02*
Y55512D01*
G01X274606D02*
Y43701D01*
G01X254921D02*
Y55512D01*
G01X284843Y59449D02*
X296654D01*
G01X258858D02*
X270669D01*
G01X284843Y106693D02*
G03Y114567I0J3937D01*
G01X280906Y278741D02*
G03X284843Y274804I3937J0D01*
G01X270669D02*
G03X274606Y278741I0J3937D01*
G01X254921D02*
G03X258858Y274804I3937J0D01*
G01X280906Y278741D02*
Y290552D01*
G01X274606D02*
Y278741D01*
G01X254921D02*
Y290552D01*
G01X270669Y274804D02*
X258858D01*
G01X296654D02*
X284843D01*
G01Y294489D02*
G03X280906Y290552I0J-3937D01*
G01X258858Y294489D02*
G03X254921Y290552I0J-3937D01*
G01X274606D02*
G03X270669Y294489I-3937J0D01*
G01X284843D02*
X296654D01*
G01X258858D02*
X270669D01*
G01X284843Y341733D02*
G03Y349607I0J3937D01*
G01X280906Y513780D02*
G03X284843Y509843I3937J0D01*
G01Y529528D02*
G03X280906Y525591I0J-3937D01*
G01X270669Y509843D02*
G03X274606Y513780I0J3937D01*
G01X254921D02*
G03X258858Y509843I3937J0D01*
G01Y529528D02*
G03X254921Y525591I0J-3937D01*
G01X274606D02*
G03X270669Y529528I-3937J0D01*
G01X280906Y513780D02*
Y525591D01*
G01X274606D02*
Y513780D01*
G01X254921D02*
Y525591D01*
G01X284843Y529528D02*
X296654D01*
G01X258858D02*
X270669D01*
G01Y509843D02*
X258858D01*
G01X296654D02*
X284843D01*
G01Y576772D02*
G03Y584646I0J3937D01*
G01X322638Y39764D02*
G03X326575Y43701I0J3937D01*
G01X306890D02*
G03X310827Y39764I3937J0D01*
G01X296654D02*
G03X300591Y43701I0J3937D01*
G01X322638Y39764D02*
X310827D01*
G01X308858Y29331D02*
G03X301378I-3740J0D01*
G01X350984Y0D02*
X352953Y1969D01*
G01X308858D02*
Y29331D01*
G01X299409Y0D02*
X301378Y1969D01*
G01D02*
Y29331D01*
G01X308858Y1969D02*
X310827Y0D01*
G01X350984D02*
X310827D01*
G01Y59449D02*
G03X306890Y55512I0J-3937D01*
G01X326575D02*
G03X322638Y59449I-3937J0D01*
G01X300591Y55512D02*
G03X296654Y59449I-3937J0D01*
G01X326575Y55512D02*
Y43701D01*
G01X306890D02*
Y55512D01*
G01X300591D02*
Y43701D01*
G01X310827Y59449D02*
X322638D01*
G01X315551Y114567D02*
G03Y106693I0J-3937D01*
G01X352953Y219292D02*
X350984Y221260D01*
G01X322638Y274804D02*
G03X326575Y278741I0J3937D01*
G01X306890D02*
G03X310827Y274804I3937J0D01*
G01X296654D02*
G03X300591Y278741I0J3937D01*
G01X326575Y290552D02*
Y278741D01*
G01X306890D02*
Y290552D01*
G01X300591D02*
Y278741D01*
G01X322638Y274804D02*
X310827D01*
G01X308858Y264370D02*
G03X301378I-3740J0D01*
G01X350984Y235040D02*
X352953Y237008D01*
G01X308858D02*
Y264370D01*
G01X299409Y235040D02*
X301378Y237008D01*
G01D02*
Y264370D01*
G01X308858Y237008D02*
X310827Y235040D01*
G01X350984D02*
X310827D01*
G01Y294489D02*
G03X306890Y290552I0J-3937D01*
G01X326575D02*
G03X322638Y294489I-3937J0D01*
G01X300591Y290552D02*
G03X296654Y294489I-3937J0D01*
G01X310827D02*
X322638D01*
G01X315551Y349607D02*
G03Y341733I0J-3937D01*
G01X352953Y454331D02*
X350984Y456300D01*
G01X322638Y509843D02*
G03X326575Y513780I0J3937D01*
G01X306890D02*
G03X310827Y509843I3937J0D01*
G01Y529528D02*
G03X306890Y525591I0J-3937D01*
G01X326575D02*
G03X322638Y529528I-3937J0D01*
G01X300591Y525591D02*
G03X296654Y529528I-3937J0D01*
G01Y509843D02*
G03X300591Y513780I0J3937D01*
G01X326575Y525591D02*
Y513780D01*
G01X306890D02*
Y525591D01*
G01X300591D02*
Y513780D01*
G01X310827Y529528D02*
X322638D01*
G01Y509843D02*
X310827D01*
G01X308858Y499410D02*
G03X301378I-3740J0D01*
G01X350984Y470079D02*
X352953Y472048D01*
G01X308858D02*
Y499410D01*
G01X299409Y470079D02*
X301378Y472048D01*
G01D02*
Y499410D01*
G01X308858Y472048D02*
X310827Y470079D01*
G01X350984D02*
X310827D01*
G01X315551Y584646D02*
G03Y576772I0J-3937D01*
G01X352953Y689371D02*
X350984Y691339D01*
G01X381890Y37795D02*
G03X385827Y33858I3937J0D01*
G01X402953Y29921D02*
G03X399016Y33858I-3937J0D01*
G01X385827D02*
X399016D01*
G01X681299Y0D02*
X404921D01*
G01X402953Y1969D02*
X404921Y0D01*
G01X402953Y1969D02*
Y29921D01*
G01X381890Y102756D02*
Y37795D01*
G01X352953Y1969D02*
Y59941D01*
G01D02*
Y33858D01*
G01X385827Y106693D02*
G03X381890Y102756I0J-3937D01*
G01X374016D02*
G03X370079Y106693I-3937J0D01*
G01Y63878D02*
G03X374016Y67815I0J3937D01*
G01X356890Y63878D02*
G03X352953Y59941I0J-3937D01*
G01X374016Y102756D02*
Y67815D01*
G01X370079Y63878D02*
X356890D01*
G01X374016Y98524D02*
G03X381890I3937J0D01*
G01Y67815D02*
G03X374016I-3937J0D01*
G01X385827Y106693D02*
X525591D01*
G01X370079Y114567D02*
G03X374016Y118504I0J3937D01*
G01D02*
Y183465D01*
G01X381890Y118504D02*
G03X385827Y114567I3937J0D01*
G01Y157382D02*
G03X381890Y153445I0J-3937D01*
G01X399016Y157382D02*
G03X402953Y161319I0J3937D01*
G01X381890Y118504D02*
Y153445D01*
G01X402953Y219292D02*
Y161319D01*
G01D02*
Y187402D01*
G01X525591Y114567D02*
X385827D01*
G01Y157382D02*
X399016D01*
G01X374016Y153445D02*
G03X381890I3937J0D01*
G01Y122737D02*
G03X374016I-3937J0D01*
G01Y183465D02*
G03X370079Y187402I-3937J0D01*
G01X352953Y191339D02*
G03X356890Y187402I3937J0D01*
G01X370079D02*
X356890D01*
G01X352953Y219292D02*
Y191339D01*
G01X404921Y221260D02*
X402953Y219292D01*
G01X404921Y221260D02*
X445079D01*
G01X352953Y237008D02*
Y294981D01*
G01D02*
Y268898D01*
G01X381890Y272835D02*
G03X385827Y268898I3937J0D01*
G01X402953Y264961D02*
G03X399016Y268898I-3937J0D01*
G01X385827D02*
X399016D01*
G01X681299Y235040D02*
X404921D01*
G01X402953Y237008D02*
X404921Y235040D01*
G01X402953Y237008D02*
Y264961D01*
G01X381890Y337796D02*
Y272835D01*
G01X374016Y337796D02*
G03X370079Y341733I-3937J0D01*
G01Y298918D02*
G03X374016Y302855I0J3937D01*
G01X356890Y298918D02*
G03X352953Y294981I0J-3937D01*
G01X374016Y337796D02*
Y302855D01*
G01X370079Y298918D02*
X356890D01*
G01X385827Y341733D02*
G03X381890Y337796I0J-3937D01*
G01X385827Y341733D02*
X525591D01*
G01X374016Y333563D02*
G03X381890I3937J0D01*
G01Y302855D02*
G03X374016I-3937J0D01*
G01X381890Y353544D02*
G03X385827Y349607I3937J0D01*
G01Y392422D02*
G03X381890Y388485I0J-3937D01*
G01X399016Y392422D02*
G03X402953Y396359I0J3937D01*
G01X381890Y353544D02*
Y388485D01*
G01X402953Y454331D02*
Y396359D01*
G01D02*
Y422441D01*
G01X525591Y349607D02*
X385827D01*
G01Y392422D02*
X399016D01*
G01X370079Y349607D02*
G03X374016Y353544I0J3937D01*
G01D02*
Y418504D01*
G01Y388485D02*
G03X381890I3937J0D01*
G01Y357776D02*
G03X374016I-3937J0D01*
G01X404921Y456300D02*
X402953Y454331D01*
G01X404921Y456300D02*
X445079D01*
G01X374016Y418504D02*
G03X370079Y422441I-3937J0D01*
G01X352953Y426378D02*
G03X356890Y422441I3937J0D01*
G01X370079D02*
X356890D01*
G01X352953Y454331D02*
Y426378D01*
G01Y472048D02*
Y530020D01*
G01D02*
Y503937D01*
G01X381890Y507874D02*
G03X385827Y503937I3937J0D01*
G01X402953Y500000D02*
G03X399016Y503937I-3937J0D01*
G01X385827D02*
X399016D01*
G01X681299Y470079D02*
X404921D01*
G01X402953Y472048D02*
X404921Y470079D01*
G01X402953Y472048D02*
Y500000D01*
G01X381890Y572835D02*
Y507874D01*
G01X374016Y572835D02*
G03X370079Y576772I-3937J0D01*
G01Y533957D02*
G03X374016Y537894I0J3937D01*
G01X356890Y533957D02*
G03X352953Y530020I0J-3937D01*
G01X374016Y572835D02*
Y537894D01*
G01X370079Y533957D02*
X356890D01*
G01X385827Y576772D02*
G03X381890Y572835I0J-3937D01*
G01X385827Y576772D02*
X525591D01*
G01X381890Y588583D02*
G03X385827Y584646I3937J0D01*
G01X381890Y588583D02*
Y623524D01*
G01X525591Y584646D02*
X385827D01*
G01X370079D02*
G03X374016Y588583I0J3937D01*
G01D02*
Y653544D01*
G01Y568603D02*
G03X381890I3937J0D01*
G01Y537894D02*
G03X374016I-3937J0D01*
G01X385827Y627461D02*
G03X381890Y623524I0J-3937D01*
G01X399016Y627461D02*
G03X402953Y631398I0J3937D01*
G01Y689371D02*
Y631398D01*
G01D02*
Y657481D01*
G01X385827Y627461D02*
X399016D01*
G01X374016Y623524D02*
G03X381890I3937J0D01*
G01Y592816D02*
G03X374016I-3937J0D01*
G01X404921Y691339D02*
X402953Y689371D01*
G01X404921Y691339D02*
X445079D01*
G01X374016Y653544D02*
G03X370079Y657481I-3937J0D01*
G01X352953Y661418D02*
G03X356890Y657481I3937J0D01*
G01X370079D02*
X356890D01*
G01X352953Y689371D02*
Y661418D01*
G01X445079Y161811D02*
G03X449016Y165748I0J3937D01*
G01X429331D02*
G03X433268Y161811I3937J0D01*
G01X455315Y165748D02*
G03X459252Y161811I3937J0D01*
G01X471063D02*
G03X475000Y165748I0J3937D01*
G01X445079Y161811D02*
X433268D01*
G01X471063D02*
X459252D01*
G01X471063Y114567D02*
G03Y106693I0J-3937D01*
G01X440354D02*
G03Y114567I0J3937D01*
G01X433268Y181496D02*
G03X429331Y177559I0J-3937D01*
G01X449016D02*
G03X445079Y181496I-3937J0D01*
G01X459252D02*
G03X455315Y177559I0J-3937D01*
G01X475000D02*
G03X471063Y181496I-3937J0D01*
G01X429331Y165748D02*
Y177559D01*
G01X449016D02*
Y165748D01*
G01X455315D02*
Y177559D01*
G01X459252Y181496D02*
X471063D01*
G01X433268D02*
X445079D01*
G01X447047Y191930D02*
G03X454528I3740J0D01*
G01X447047Y219292D02*
Y191930D01*
G01X456496Y221260D02*
X454528Y219292D01*
G01D02*
Y191930D01*
G01X447047Y219292D02*
X445079Y221260D01*
G01X456496D02*
X732874D01*
G01X471063Y349607D02*
G03Y341733I0J-3937D01*
G01X440354D02*
G03Y349607I0J3937D01*
G01X445079Y396851D02*
G03X449016Y400788I0J3937D01*
G01X429331D02*
G03X433268Y396851I3937J0D01*
G01X455315Y400788D02*
G03X459252Y396851I3937J0D01*
G01X471063D02*
G03X475000Y400788I0J3937D01*
G01X429331D02*
Y412599D01*
G01X449016D02*
Y400788D01*
G01X455315D02*
Y412599D01*
G01X445079Y396851D02*
X433268D01*
G01X471063D02*
X459252D01*
G01X433268Y416536D02*
G03X429331Y412599I0J-3937D01*
G01X449016D02*
G03X445079Y416536I-3937J0D01*
G01X459252D02*
G03X455315Y412599I0J-3937D01*
G01X475000D02*
G03X471063Y416536I-3937J0D01*
G01X459252D02*
X471063D01*
G01X433268D02*
X445079D01*
G01X447047Y426969D02*
G03X454528I3740J0D01*
G01X447047Y454331D02*
Y426969D01*
G01X456496Y456300D02*
X454528Y454331D01*
G01D02*
Y426969D01*
G01X447047Y454331D02*
X445079Y456300D01*
G01X456496D02*
X732874D01*
G01X471063Y584646D02*
G03Y576772I0J-3937D01*
G01X440354D02*
G03Y584646I0J3937D01*
G01X433268Y651576D02*
G03X429331Y647639I0J-3937D01*
G01X449016D02*
G03X445079Y651576I-3937J0D01*
G01Y631891D02*
G03X449016Y635828I0J3937D01*
G01X429331D02*
G03X433268Y631891I3937J0D01*
G01X455315Y635828D02*
G03X459252Y631891I3937J0D01*
G01Y651576D02*
G03X455315Y647639I0J-3937D01*
G01X475000D02*
G03X471063Y651576I-3937J0D01*
G01Y631891D02*
G03X475000Y635828I0J3937D01*
G01X429331D02*
Y647639D01*
G01X449016D02*
Y635828D01*
G01X455315D02*
Y647639D01*
G01X445079Y631891D02*
X433268D01*
G01X471063D02*
X459252D01*
G01Y651576D02*
X471063D01*
G01X433268D02*
X445079D01*
G01X447047Y662009D02*
G03X454528I3740J0D01*
G01X447047Y689371D02*
Y662009D01*
G01X456496Y691339D02*
X454528Y689371D01*
G01D02*
Y662009D01*
G01X447047Y689371D02*
X445079Y691339D01*
G01X456496D02*
X732874D01*
G01X529528Y102756D02*
G03X533465Y98819I3937J0D01*
G01X529528Y102756D02*
G03X525591Y106693I-3937J0D01*
G01X529528Y102756D02*
G03X533465Y98819I3937J0D01*
G01X529528Y102756D02*
G03X525591Y106693I-3937J0D01*
G01X529528Y102756D02*
G03X533465Y98819I3937J0D01*
G01X529528Y102756D02*
G03X525591Y106693I-3937J0D01*
G01X533465Y98819D02*
X604331D01*
G01X525591Y106693D02*
X494094D01*
G01X497047Y161811D02*
G03X500984Y165748I0J3937D01*
G01X481299D02*
G03X485236Y161811I3937J0D01*
G01X497047D02*
X485236D01*
G01X533465Y122441D02*
G03X529528Y118504I0J-3937D01*
G01X525591Y114567D02*
G03X529528Y118504I0J3937D01*
G01X525591Y114567D02*
X494094D01*
G01X525591D02*
G03X529528Y118504I0J3937D01*
G01X533465Y122441D02*
G03X529528Y118504I0J-3937D01*
G01X533465Y122441D02*
G03X529528Y118504I0J-3937D01*
G01X525591Y114567D02*
G03X529528Y118504I0J3937D01*
G01X604331Y122441D02*
X533465D01*
G01X485236Y181496D02*
G03X481299Y177559I0J-3937D01*
G01X500984D02*
G03X497047Y181496I-3937J0D01*
G01X475000Y177559D02*
Y165748D01*
G01X481299D02*
Y177559D01*
G01X500984D02*
Y165748D01*
G01X485236Y181496D02*
X497047D01*
G01X529528Y337796D02*
G03X533465Y333859I3937J0D01*
G01X529528Y337796D02*
G03X525591Y341733I-3937J0D01*
G01D02*
X494094D01*
G01X529528Y337796D02*
G03X533465Y333859I3937J0D01*
G01X529528Y337796D02*
G03X525591Y341733I-3937J0D01*
G01X529528Y337796D02*
G03X533465Y333859I3937J0D01*
G01X529528Y337796D02*
G03X525591Y341733I-3937J0D01*
G01X533465Y333859D02*
X604331D01*
G01X497047Y396851D02*
G03X500984Y400788I0J3937D01*
G01X481299D02*
G03X485236Y396851I3937J0D01*
G01X475000Y412599D02*
Y400788D01*
G01X481299D02*
Y412599D01*
G01X500984D02*
Y400788D01*
G01X497047Y396851D02*
X485236D01*
G01X533465Y357481D02*
G03X529528Y353544I0J-3937D01*
G01X525591Y349607D02*
G03X529528Y353544I0J3937D01*
G01X525591Y349607D02*
X494094D01*
G01X525591D02*
G03X529528Y353544I0J3937D01*
G01X533465Y357481D02*
G03X529528Y353544I0J-3937D01*
G01X533465Y357481D02*
G03X529528Y353544I0J-3937D01*
G01X525591Y349607D02*
G03X529528Y353544I0J3937D01*
G01X604331Y357481D02*
X533465D01*
G01X485236Y416536D02*
G03X481299Y412599I0J-3937D01*
G01X500984D02*
G03X497047Y416536I-3937J0D01*
G01X485236D02*
X497047D01*
G01X529528Y572835D02*
G03X533465Y568898I3937J0D01*
G01X529528Y572835D02*
G03X525591Y576772I-3937J0D01*
G01D02*
X494094D01*
G01X529528Y572835D02*
G03X533465Y568898I3937J0D01*
G01X529528Y572835D02*
G03X525591Y576772I-3937J0D01*
G01X529528Y572835D02*
G03X533465Y568898I3937J0D01*
G01X529528Y572835D02*
G03X525591Y576772I-3937J0D01*
G01X533465Y568898D02*
X604331D01*
G01X533465Y592520D02*
G03X529528Y588583I0J-3937D01*
G01X525591Y584646D02*
G03X529528Y588583I0J3937D01*
G01X525591Y584646D02*
X494094D01*
G01X525591D02*
G03X529528Y588583I0J3937D01*
G01X533465Y592520D02*
G03X529528Y588583I0J-3937D01*
G01X533465Y592520D02*
G03X529528Y588583I0J-3937D01*
G01X525591Y584646D02*
G03X529528Y588583I0J3937D01*
G01X485236Y651576D02*
G03X481299Y647639I0J-3937D01*
G01X500984D02*
G03X497047Y651576I-3937J0D01*
G01Y631891D02*
G03X500984Y635828I0J3937D01*
G01X481299D02*
G03X485236Y631891I3937J0D01*
G01X475000Y647639D02*
Y635828D01*
G01X481299D02*
Y647639D01*
G01X500984D02*
Y635828D01*
G01X497047Y631891D02*
X485236D01*
G01Y651576D02*
X497047D01*
G01X604331Y592520D02*
X533465D01*
G01X652559Y39764D02*
G03X656496Y43701I0J3937D01*
G01X636811D02*
G03X640748Y39764I3937J0D01*
G01X652559D02*
X640748D01*
G01Y59449D02*
G03X636811Y55512I0J-3937D01*
G01X656496D02*
G03X652559Y59449I-3937J0D01*
G01X656496Y55512D02*
Y43701D01*
G01X636811D02*
Y55512D01*
G01X640748Y59449D02*
X652559D01*
G01X604331Y98819D02*
G03X608268Y102756I0J3937D01*
G01X612205Y106693D02*
G03X608268Y102756I0J-3937D01*
G01X612205Y106693D02*
G03X608268Y102756I0J-3937D01*
G01X604331Y98819D02*
G03X608268Y102756I0J3937D01*
G01X604331Y98819D02*
G03X608268Y102756I0J3937D01*
G01X612205Y106693D02*
G03X608268Y102756I0J-3937D01*
G01X612205Y106693D02*
X643701D01*
G01X612205D02*
X751969D01*
G01X608268Y118504D02*
G03X604331Y122441I-3937J0D01*
G01X608268Y118504D02*
G03X612205Y114567I3937J0D01*
G01D02*
X643701D01*
G01X608268Y118504D02*
G03X604331Y122441I-3937J0D01*
G01X608268Y118504D02*
G03X612205Y114567I3937J0D01*
G01X608268Y118504D02*
G03X604331Y122441I-3937J0D01*
G01X608268Y118504D02*
G03X612205Y114567I3937J0D01*
G01X751969D02*
X612205D01*
G01X652559Y274804D02*
G03X656496Y278741I0J3937D01*
G01X636811D02*
G03X640748Y274804I3937J0D01*
G01X656496Y290552D02*
Y278741D01*
G01X636811D02*
Y290552D01*
G01X652559Y274804D02*
X640748D01*
G01Y294489D02*
G03X636811Y290552I0J-3937D01*
G01X656496D02*
G03X652559Y294489I-3937J0D01*
G01X640748D02*
X652559D01*
G01X604331Y333859D02*
G03X608268Y337796I0J3937D01*
G01X612205Y341733D02*
G03X608268Y337796I0J-3937D01*
G01X612205Y341733D02*
X643701D01*
G01X612205D02*
G03X608268Y337796I0J-3937D01*
G01X604331Y333859D02*
G03X608268Y337796I0J3937D01*
G01X604331Y333859D02*
G03X608268Y337796I0J3937D01*
G01X612205Y341733D02*
G03X608268Y337796I0J-3937D01*
G01X612205Y341733D02*
X751969D01*
G01X608268Y353544D02*
G03X604331Y357481I-3937J0D01*
G01X608268Y353544D02*
G03X612205Y349607I3937J0D01*
G01D02*
X643701D01*
G01X608268Y353544D02*
G03X604331Y357481I-3937J0D01*
G01X608268Y353544D02*
G03X612205Y349607I3937J0D01*
G01X608268Y353544D02*
G03X604331Y357481I-3937J0D01*
G01X608268Y353544D02*
G03X612205Y349607I3937J0D01*
G01X751969D02*
X612205D01*
G01X652559Y509843D02*
G03X656496Y513780I0J3937D01*
G01X636811D02*
G03X640748Y509843I3937J0D01*
G01Y529528D02*
G03X636811Y525591I0J-3937D01*
G01X656496D02*
G03X652559Y529528I-3937J0D01*
G01X656496Y525591D02*
Y513780D01*
G01X636811D02*
Y525591D01*
G01X640748Y529528D02*
X652559D01*
G01Y509843D02*
X640748D01*
G01X604331Y568898D02*
G03X608268Y572835I0J3937D01*
G01X612205Y576772D02*
G03X608268Y572835I0J-3937D01*
G01X612205Y576772D02*
X643701D01*
G01X612205D02*
G03X608268Y572835I0J-3937D01*
G01X604331Y568898D02*
G03X608268Y572835I0J3937D01*
G01X604331Y568898D02*
G03X608268Y572835I0J3937D01*
G01X612205Y576772D02*
G03X608268Y572835I0J-3937D01*
G01X612205Y576772D02*
X751969D01*
G01X608268Y588583D02*
G03X604331Y592520I-3937J0D01*
G01X608268Y588583D02*
G03X612205Y584646I3937J0D01*
G01D02*
X643701D01*
G01X608268Y588583D02*
G03X604331Y592520I-3937J0D01*
G01X608268Y588583D02*
G03X612205Y584646I3937J0D01*
G01X608268Y588583D02*
G03X604331Y592520I-3937J0D01*
G01X608268Y588583D02*
G03X612205Y584646I3937J0D01*
G01X751969D02*
X612205D01*
G01X704528Y39764D02*
G03X708465Y43701I0J3937D01*
G01X688780D02*
G03X692717Y39764I3937J0D01*
G01X678543D02*
G03X682480Y43701I0J3937D01*
G01X662795D02*
G03X666732Y39764I3937J0D01*
G01X678543D02*
X666732D01*
G01X704528D02*
X692717D01*
G01X690748Y29331D02*
G03X683268I-3740J0D01*
G01X690748Y1969D02*
Y29331D01*
G01X681299Y0D02*
X683268Y1969D01*
G01D02*
Y29331D01*
G01X690748Y1969D02*
X692717Y0D01*
G01X732874D02*
X692717D01*
G01Y59449D02*
G03X688780Y55512I0J-3937D01*
G01X708465D02*
G03X704528Y59449I-3937J0D01*
G01X682480Y55512D02*
G03X678543Y59449I-3937J0D01*
G01X666732D02*
G03X662795Y55512I0J-3937D01*
G01X708465D02*
Y43701D01*
G01X688780D02*
Y55512D01*
G01X682480D02*
Y43701D01*
G01X662795D02*
Y55512D01*
G01X692717Y59449D02*
X704528D01*
G01X666732D02*
X678543D01*
G01X697441Y114567D02*
G03Y106693I0J-3937D01*
G01X666732D02*
G03Y114567I0J3937D01*
G01X704528Y274804D02*
G03X708465Y278741I0J3937D01*
G01X688780D02*
G03X692717Y274804I3937J0D01*
G01X678543D02*
G03X682480Y278741I0J3937D01*
G01X662795D02*
G03X666732Y274804I3937J0D01*
G01X708465Y290552D02*
Y278741D01*
G01X688780D02*
Y290552D01*
G01X682480D02*
Y278741D01*
G01X662795D02*
Y290552D01*
G01X678543Y274804D02*
X666732D01*
G01X704528D02*
X692717D01*
G01X690748Y264370D02*
G03X683268I-3740J0D01*
G01X690748Y237008D02*
Y264370D01*
G01X681299Y235040D02*
X683268Y237008D01*
G01D02*
Y264370D01*
G01X690748Y237008D02*
X692717Y235040D01*
G01X732874D02*
X692717D01*
G01Y294489D02*
G03X688780Y290552I0J-3937D01*
G01X708465D02*
G03X704528Y294489I-3937J0D01*
G01X682480Y290552D02*
G03X678543Y294489I-3937J0D01*
G01X666732D02*
G03X662795Y290552I0J-3937D01*
G01X692717Y294489D02*
X704528D01*
G01X666732D02*
X678543D01*
G01X697441Y349607D02*
G03Y341733I0J-3937D01*
G01X666732D02*
G03Y349607I0J3937D01*
G01X704528Y509843D02*
G03X708465Y513780I0J3937D01*
G01X688780D02*
G03X692717Y509843I3937J0D01*
G01Y529528D02*
G03X688780Y525591I0J-3937D01*
G01X708465D02*
G03X704528Y529528I-3937J0D01*
G01X682480Y525591D02*
G03X678543Y529528I-3937J0D01*
G01Y509843D02*
G03X682480Y513780I0J3937D01*
G01X662795D02*
G03X666732Y509843I3937J0D01*
G01Y529528D02*
G03X662795Y525591I0J-3937D01*
G01X708465D02*
Y513780D01*
G01X688780D02*
Y525591D01*
G01X682480D02*
Y513780D01*
G01X662795D02*
Y525591D01*
G01X692717Y529528D02*
X704528D01*
G01X666732D02*
X678543D01*
G01Y509843D02*
X666732D01*
G01X704528D02*
X692717D01*
G01X690748Y499410D02*
G03X683268I-3740J0D01*
G01X690748Y472048D02*
Y499410D01*
G01X681299Y470079D02*
X683268Y472048D01*
G01D02*
Y499410D01*
G01X690748Y472048D02*
X692717Y470079D01*
G01X732874D02*
X692717D01*
G01X697441Y584646D02*
G03Y576772I0J-3937D01*
G01X666732D02*
G03Y584646I0J3937D01*
G01X734843Y1969D02*
Y59941D01*
G01D02*
Y33858D01*
G01X732874Y0D02*
X734843Y1969D01*
G01X762744Y17317D02*
G03I-4292J0D01*
G01X775591Y553149D02*
Y15000D01*
G01X760591Y0D02*
G03X775591Y15000I0J15000D01*
G01X742717Y0D02*
Y56004D01*
G01Y0D02*
X760591D01*
G01X755906Y102756D02*
G03X751969Y106693I-3937J0D01*
G01Y63878D02*
G03X755906Y67815I0J3937D01*
G01X738780Y63878D02*
G03X734843Y59941I0J-3937D01*
G01X755906Y102756D02*
Y67815D01*
G01X751969Y63878D02*
X738780D01*
G01X763780Y152761D02*
Y98517D01*
G01Y67822D02*
Y67803D01*
G01X751969Y56004D02*
X742717D01*
G01X751969D02*
G03X763780Y67815I0J11811D01*
G01D02*
G03X755906I-3937J0D01*
G01Y98524D02*
G03X763780I3937J0D01*
G01X751969Y114567D02*
G03X755906Y118504I0J3937D01*
G01D02*
Y183465D01*
G01X763780Y152756D02*
G03X755906I-3937J0D01*
G01Y183465D02*
G03X751969Y187402I-3937J0D01*
G01X734843Y191339D02*
G03X738780Y187402I3937J0D01*
G01X751969D02*
X738780D01*
G01X734843Y219292D02*
X732874Y221260D01*
G01X734843Y219292D02*
Y191339D01*
G01X755906Y183465D02*
G03X763780I3937J0D01*
G01Y302855D02*
Y183460D01*
G01X734843Y237008D02*
Y294981D01*
G01D02*
Y268898D01*
G01X732874Y235040D02*
X734843Y237008D01*
G01X755906Y337796D02*
G03X751969Y341733I-3937J0D01*
G01Y298918D02*
G03X755906Y302855I0J3937D01*
G01X738780Y298918D02*
G03X734843Y294981I0J-3937D01*
G01X755906Y337796D02*
Y302855D01*
G01X751969Y298918D02*
X738780D01*
G01X763780Y387796D02*
Y333559D01*
G01Y302855D02*
G03X755906I-3937J0D01*
G01Y333563D02*
G03X763780I3937J0D01*
G01X751969Y349607D02*
G03X755906Y353544I0J3937D01*
G01D02*
Y418504D01*
G01X763780Y387796D02*
G03X755906I-3937J0D01*
G01Y418504D02*
G03X751969Y422441I-3937J0D01*
G01X734843Y426378D02*
G03X738780Y422441I3937J0D01*
G01X751969D02*
X738780D01*
G01X734843Y454331D02*
X732874Y456300D01*
G01X734843Y454331D02*
Y426378D01*
G01X763780Y537894D02*
Y418504D01*
G01X755906Y418505D02*
G03X763780I3937J0D01*
G01X734843Y472048D02*
Y530020D01*
G01D02*
Y503937D01*
G01X732874Y470079D02*
X734843Y472048D01*
G01X755906Y572835D02*
G03X751969Y576772I-3937J0D01*
G01Y533957D02*
G03X755906Y537894I0J3937D01*
G01X738780Y533957D02*
G03X734843Y530020I0J-3937D01*
G01X755906Y572835D02*
Y537894D01*
G01X751969Y533957D02*
X738780D01*
G01X751969Y584646D02*
G03X755906Y588583I0J3937D01*
G01D02*
Y653544D01*
G01X775591Y561023D02*
G03Y553149I0J-3937D01*
G01X763780Y537894D02*
G03X755906I-3937J0D01*
G01Y568603D02*
G03X763780I3937J0D01*
G01X775591Y676339D02*
Y561023D01*
G01X763780Y622835D02*
Y568603D01*
G01Y622835D02*
G03X755906I-3937J0D01*
G01Y653544D02*
G03X763780I3937J0D01*
G01X755906D02*
G03X751969Y657481I-3937J0D01*
G01X734843Y661418D02*
G03X738780Y657481I3937J0D01*
G01X751969D02*
X738780D01*
G01X734843Y689371D02*
X732874Y691339D01*
G01X734843Y689371D02*
Y661418D01*
G01X760014Y677788D02*
G03I-4292J0D01*
G01X775591Y676339D02*
G03X760591Y691339I-15000J0D01*
G01X751969Y665355D02*
X742717D01*
G01X763780Y653544D02*
G03X751969Y665355I-11811J0D01*
G01X742717Y691339D02*
X760591D01*
G01X742717Y665355D02*
Y691339D01*
M02*
